FILE_TYPE = MULTI_PHYS_TABLE;

PART 'BAT547F'

{========================================================================================}
:VALUE     | PART_TYPE | MATERIAL | PART_NUMBER    = STANDARD | LIFECYCLE | PART_NUMBER   | JEDEC_TYPE    | DESCRIPTION                           | MANUFTR | MANUF_PN    | RD_CMPLS_LVL | CMPLS_LVL | CLASS | DIP_SMD | FP_ECN | FROM_PJ     | DATA                           | EE_CHECK_LIST | STATUS | PSL | PREFERENCE | CREATOR | CREATEDAY  ;
{========================================================================================}
 'BAT547F' | 'SMLF'    | 'IC'     | 'BC0BAT54Z53'(!) = ''       | ''        | 'BC0BAT54Z53' |'SOT23_123XB'| 'DIODE BAT54-7-F(30V.200MA SCHOTTKY)' | 'DDS'   | 'BAT54-7-F' | ''           | 'EU'      | 'IC'  | ''      | ''     | 'S50-STEVE' | 'DDS_BAT54-7-F(A.C.S-7-F).pdf' | ''            | ''     | ''  | ''         | ''      | '20130912'
 'BAT547F' | 'SMLF'    | 'EMPTY'  | 'BC0BAT54Z53'(!) = ''       | ''        | 'BC0BAT54Z53' |'SOT23_123XB'| 'DIODE BAT54-7-F(30V.200MA SCHOTTKY)' | 'DDS'   | 'BAT54-7-F' | ''           | 'EU'      | 'IC'  | ''      | ''     | 'S50-STEVE' | 'DDS_BAT54-7-F(A.C.S-7-F).pdf' | ''            | ''     | ''  | ''         | ''      | '20130912'

END_PART

END.

